#ISCELL
  mstr_misc dns *
  *
#ISCELL
  mstr_symbols cad_note *
  *
#ISCELL
  mstr_symbols design_note *
  *
#ISCELL
  mstr_symbols intel_corp_bpage *
  *
#ISCELL
  mstr_standard offpage *
  page166_i16
#ISCELL
  mstr_standard offpage *
  page166_i17
#CELL
  mstr_discrete res *
  page166_i28
#ISCELL
  mstr_symbols pvccio_cpu0 *
  page166_i31
#CELL
  mstr_discrete res *
  page166_i32
#ISCELL
  mstr_symbols gnd *
  page166_i33
#CELL
  w_hdl pi5a3157bc6e-gp *
  page166_i34
#CELL
  dev_discrete cap_a *
  page166_i36
#ISCELL
  mstr_symbols gnd *
  page166_i37
#ISCELL
  mstr_standard offpage *
  page166_i38
#ISCELL
  mstr_standard offpage *
  page166_i39
#ISCELL
  mstr_symbols p3v3_stby *
  page166_i40
#ISCELL
  mstr_symbols gnd *
  page166_i41
#CELL
  mstr_discrete res *
  page166_i42
#ISCELL
  mstr_symbols gnd *
  page166_i43
#ISCELL
  mstr_symbols p3v3_stby *
  page166_i45
#CELL
  mstr_discrete res *
  page166_i46
